(kicad_pcb
	(version 20260206)
	(generator "pcbnew")
	(generator_version "10.0")
	(general
		(thickness 1.6)
		(legacy_teardrops no)
	)
	(paper "A4")
	(title_block
		(title "v1-chassis-manager — T6M_CM_d_v01_1031_1645.brd")
		(comment 1 "Open CloudServer (Microsoft) / footprint 550 of 2512 (U14), pads 119-235 of 408")
	)
	(layers
		(0 "F.Cu" signal "TOP")
		(4 "In1.Cu" signal "GND1")
		(6 "In2.Cu" signal "IN1")
		(8 "In3.Cu" signal "VCC1")
		(10 "In4.Cu" signal "VCC2")
		(12 "In5.Cu" signal "GND2")
		(14 "In6.Cu" signal "IN2")
		(16 "In7.Cu" signal "IN3")
		(18 "In8.Cu" signal "GND3")
		(2 "B.Cu" signal "BOTTOM")
		(9 "F.Adhes" user "F.Adhesive")
		(11 "B.Adhes" user "B.Adhesive")
		(13 "F.Paste" user "Package Geometry/Pastemask Top")
		(15 "B.Paste" user "Package Geometry/Pastemask Bottom")
		(5 "F.SilkS" user "Ref Des/Silkscreen Top")
		(7 "B.SilkS" user "Ref Des/Silkscreen Bottom")
		(1 "F.Mask" user "Board Geometry/Soldermask Top")
		(3 "B.Mask" user "Board Geometry/Soldermask Bottom")
		(17 "Dwgs.User" user "User.Drawings")
		(19 "Cmts.User" user "User.Comments")
		(21 "Eco1.User" user "User.Eco1")
		(23 "Eco2.User" user "User.Eco2")
		(25 "Edge.Cuts" user "Board Geometry/Outline")
		(27 "Margin" user)
		(31 "F.CrtYd" user "Package Geometry/Place Bound Top")
		(29 "B.CrtYd" user "Package Geometry/Place Bound Bottom")
		(35 "F.Fab" user "Ref Des/Assembly Top")
		(33 "B.Fab" user "Ref Des/Assembly Bottom")
	)
	(footprint ""
		(layer "F.Cu")
		(at 65.741804 -134.859522 -90)
		(property "Reference" "U14"
			(at 12.258294 13.71092 90)
			(unlocked yes)
			(layer "F.SilkS")
			(effects
				(font
					(size 1.6002 1.1938)
					(thickness 0.1524)
				)
				(justify left)
			)
		)
		(property "Value" ""
			(at 0 0 270)
			(layer "F.Fab")
			(effects
				(font
					(size 1.27 1.27)
				)
			)
		)
		(duplicate_pad_numbers_are_jumpers no)
		(pad "D9" smd circle
			(at -1.999996 -5.999988 270)
			(size 0.3683 0.3683)
			(layers "F.Cu" "F.Mask" "F.Paste")
			(net "Net_1760")
		)
		(pad "D10" smd circle
			(at -1.199896 -5.999988 270)
			(size 0.3683 0.3683)
			(layers "F.Cu" "F.Mask" "F.Paste")
			(net "Net_1765")
		)
		(pad "D11" smd circle
			(at -0.40005 -5.999988 270)
			(size 0.3683 0.3683)
			(layers "F.Cu" "F.Mask" "F.Paste")
			(net "GND")
		)
		(pad "D12" smd circle
			(at 0.40005 -5.999988 270)
			(size 0.3683 0.3683)
			(layers "F.Cu" "F.Mask" "F.Paste")
			(net "Net_1757")
		)
		(pad "D13" smd circle
			(at 1.199896 -5.999988 270)
			(size 0.3683 0.3683)
			(layers "F.Cu" "F.Mask" "F.Paste")
			(net "Net_536")
		)
		(pad "D14" smd circle
			(at 1.999996 -5.999988 270)
			(size 0.3683 0.3683)
			(layers "F.Cu" "F.Mask" "F.Paste")
			(net "Net_1725")
		)
		(pad "D15" smd circle
			(at 2.800096 -5.999988 270)
			(size 0.3683 0.3683)
			(layers "F.Cu" "F.Mask" "F.Paste")
			(net "Net_1721")
		)
		(pad "D16" smd circle
			(at 3.599942 -5.999988 270)
			(size 0.3683 0.3683)
			(layers "F.Cu" "F.Mask" "F.Paste")
			(net "Net_1714")
		)
		(pad "D17" smd circle
			(at 4.400042 -5.999988 270)
			(size 0.3683 0.3683)
			(layers "F.Cu" "F.Mask" "F.Paste")
			(net "Net_514")
		)
		(pad "D18" smd circle
			(at 5.199888 -5.999988 270)
			(size 0.3683 0.3683)
			(layers "F.Cu" "F.Mask" "F.Paste")
			(net "Net_1728")
		)
		(pad "D19" smd circle
			(at 5.999988 -5.999988 270)
			(size 0.3683 0.3683)
			(layers "F.Cu" "F.Mask" "F.Paste")
			(net "Net_1743")
		)
		(pad "D20" smd circle
			(at 6.800088 -5.999988 270)
			(size 0.3683 0.3683)
			(layers "F.Cu" "F.Mask" "F.Paste")
			(net "PD_BMC_NODE1_PEREXT")
		)
		(pad "D21" smd circle
			(at 7.599934 -5.999988 270)
			(size 0.3683 0.3683)
			(layers "F.Cu" "F.Mask" "F.Paste")
			(net "GND")
		)
		(pad "D22" smd circle
			(at 8.400034 -5.999988 270)
			(size 0.3683 0.3683)
			(layers "F.Cu" "F.Mask" "F.Paste")
			(net "GND")
		)
		(pad "E1" smd circle
			(at -8.400034 -5.199888 270)
			(size 0.3683 0.3683)
			(layers "F.Cu" "F.Mask" "F.Paste")
			(net "BMC_NODE1_JTAG_TRST")
		)
		(pad "E2" smd circle
			(at -7.599934 -5.199888 270)
			(size 0.3683 0.3683)
			(layers "F.Cu" "F.Mask" "F.Paste")
			(net "GND")
		)
		(pad "E3" smd circle
			(at -6.800088 -5.199888 270)
			(size 0.3683 0.3683)
			(layers "F.Cu" "F.Mask" "F.Paste")
			(net "GND")
		)
		(pad "E4" smd circle
			(at -5.999988 -5.199888 270)
			(size 0.3683 0.3683)
			(layers "F.Cu" "F.Mask" "F.Paste")
			(net "N20822523")
		)
		(pad "E5" smd circle
			(at -5.199888 -5.199888 270)
			(size 0.3683 0.3683)
			(layers "F.Cu" "F.Mask" "F.Paste")
			(net "GND")
		)
		(pad "E6" smd circle
			(at -4.400042 -5.199888 270)
			(size 0.3683 0.3683)
			(layers "F.Cu" "F.Mask" "F.Paste")
			(net "N3975090767")
		)
		(pad "E7" smd circle
			(at -3.599942 -5.199888 270)
			(size 0.3683 0.3683)
			(layers "F.Cu" "F.Mask" "F.Paste")
			(net "Net_1741")
		)
		(pad "E8" smd circle
			(at -2.800096 -5.199888 270)
			(size 0.3683 0.3683)
			(layers "F.Cu" "F.Mask" "F.Paste")
			(net "GND")
		)
		(pad "E9" smd circle
			(at -1.999996 -5.199888 270)
			(size 0.3683 0.3683)
			(layers "F.Cu" "F.Mask" "F.Paste")
			(net "Net_1761")
		)
		(pad "E10" smd circle
			(at -1.199896 -5.199888 270)
			(size 0.3683 0.3683)
			(layers "F.Cu" "F.Mask" "F.Paste")
			(net "GND")
		)
		(pad "E11" smd circle
			(at -0.40005 -5.199888 270)
			(size 0.3683 0.3683)
			(layers "F.Cu" "F.Mask" "F.Paste")
			(net "GND")
		)
		(pad "E12" smd circle
			(at 0.40005 -5.199888 270)
			(size 0.3683 0.3683)
			(layers "F.Cu" "F.Mask" "F.Paste")
			(net "Net_1758")
		)
		(pad "E13" smd circle
			(at 1.199896 -5.199888 270)
			(size 0.3683 0.3683)
			(layers "F.Cu" "F.Mask" "F.Paste")
			(net "Net_535")
		)
		(pad "E14" smd circle
			(at 1.999996 -5.199888 270)
			(size 0.3683 0.3683)
			(layers "F.Cu" "F.Mask" "F.Paste")
			(net "Net_1724")
		)
		(pad "E15" smd circle
			(at 2.800096 -5.199888 270)
			(size 0.3683 0.3683)
			(layers "F.Cu" "F.Mask" "F.Paste")
			(net "Net_1720")
		)
		(pad "E16" smd circle
			(at 3.599942 -5.199888 270)
			(size 0.3683 0.3683)
			(layers "F.Cu" "F.Mask" "F.Paste")
			(net "Net_1733")
		)
		(pad "E17" smd circle
			(at 4.400042 -5.199888 270)
			(size 0.3683 0.3683)
			(layers "F.Cu" "F.Mask" "F.Paste")
			(net "PD_BMC_LPC")
		)
		(pad "E18" smd circle
			(at 5.199888 -5.199888 270)
			(size 0.3683 0.3683)
			(layers "F.Cu" "F.Mask" "F.Paste")
			(net "Net_529")
		)
		(pad "E19" smd circle
			(at 5.999988 -5.199888 270)
			(size 0.3683 0.3683)
			(layers "F.Cu" "F.Mask" "F.Paste")
			(net "Net_511")
		)
		(pad "E20" smd circle
			(at 6.800088 -5.199888 270)
			(size 0.3683 0.3683)
			(layers "F.Cu" "F.Mask" "F.Paste")
			(net "Net_1747")
		)
		(pad "E21" smd circle
			(at 7.599934 -5.199888 270)
			(size 0.3683 0.3683)
			(layers "F.Cu" "F.Mask" "F.Paste")
			(net "P2E_CPU_BMC_NODE1_RX_C_DN")
		)
		(pad "E22" smd circle
			(at 8.400034 -5.199888 270)
			(size 0.3683 0.3683)
			(layers "F.Cu" "F.Mask" "F.Paste")
			(net "P2E_CPU_BMC_NODE1_RX_C_DP")
		)
		(pad "F1" smd circle
			(at -8.400034 -4.400042 270)
			(size 0.3683 0.3683)
			(layers "F.Cu" "F.Mask" "F.Paste")
			(net "BMC_NODE1_JTAG_TDI")
		)
		(pad "F2" smd circle
			(at -7.599934 -4.400042 270)
			(size 0.3683 0.3683)
			(layers "F.Cu" "F.Mask" "F.Paste")
			(net "BMC_NODE1_JTAG_TCK")
		)
		(pad "F3" smd circle
			(at -6.800088 -4.400042 270)
			(size 0.3683 0.3683)
			(layers "F.Cu" "F.Mask" "F.Paste")
			(net "GND")
		)
		(pad "F4" smd circle
			(at -5.999988 -4.400042 270)
			(size 0.3683 0.3683)
			(layers "F.Cu" "F.Mask" "F.Paste")
			(net "GND")
		)
		(pad "F5" smd circle
			(at -5.199888 -4.400042 270)
			(size 0.3683 0.3683)
			(layers "F.Cu" "F.Mask" "F.Paste")
			(net "GND")
		)
		(pad "F8" smd circle
			(at -2.800096 -4.400042 270)
			(size 0.3683 0.3683)
			(layers "F.Cu" "F.Mask" "F.Paste")
			(net "P3V3_NODE1")
		)
		(pad "F9" smd circle
			(at -1.999996 -4.400042 270)
			(size 0.3683 0.3683)
			(layers "F.Cu" "F.Mask" "F.Paste")
			(net "P3V3_NODE1")
		)
		(pad "F10" smd circle
			(at -1.199896 -4.400042 270)
			(size 0.3683 0.3683)
			(layers "F.Cu" "F.Mask" "F.Paste")
			(net "P3V3_NODE1")
		)
		(pad "F11" smd circle
			(at -0.40005 -4.400042 270)
			(size 0.3683 0.3683)
			(layers "F.Cu" "F.Mask" "F.Paste")
			(net "P3V3_NODE1")
		)
		(pad "F12" smd circle
			(at 0.40005 -4.400042 270)
			(size 0.3683 0.3683)
			(layers "F.Cu" "F.Mask" "F.Paste")
			(net "P3V3_NODE1")
		)
		(pad "F13" smd circle
			(at 1.199896 -4.400042 270)
			(size 0.3683 0.3683)
			(layers "F.Cu" "F.Mask" "F.Paste")
			(net "P3V3_NODE1")
		)
		(pad "F14" smd circle
			(at 1.999996 -4.400042 270)
			(size 0.3683 0.3683)
			(layers "F.Cu" "F.Mask" "F.Paste")
			(net "P1V26_BMC_NODE1")
		)
		(pad "F15" smd circle
			(at 2.800096 -4.400042 270)
			(size 0.3683 0.3683)
			(layers "F.Cu" "F.Mask" "F.Paste")
			(net "P1V26_BMC_NODE1")
		)
		(pad "F18" smd circle
			(at 5.199888 -4.400042 270)
			(size 0.3683 0.3683)
			(layers "F.Cu" "F.Mask" "F.Paste")
			(net "Net_1713")
		)
		(pad "F19" smd circle
			(at 5.999988 -4.400042 270)
			(size 0.3683 0.3683)
			(layers "F.Cu" "F.Mask" "F.Paste")
			(net "PD_BMC_LPC")
		)
		(pad "F20" smd circle
			(at 6.800088 -4.400042 270)
			(size 0.3683 0.3683)
			(layers "F.Cu" "F.Mask" "F.Paste")
			(net "BMC_NODE1_VCC_1V8_PCIEA")
		)
		(pad "F21" smd circle
			(at 7.599934 -4.400042 270)
			(size 0.3683 0.3683)
			(layers "F.Cu" "F.Mask" "F.Paste")
			(net "P2E_CPU_BMC_NODE1_TX_DP")
		)
		(pad "F22" smd circle
			(at 8.400034 -4.400042 270)
			(size 0.3683 0.3683)
			(layers "F.Cu" "F.Mask" "F.Paste")
			(net "P2E_CPU_BMC_NODE1_TX_DN")
		)
		(pad "G1" smd circle
			(at -8.400034 -3.599942 270)
			(size 0.3683 0.3683)
			(layers "F.Cu" "F.Mask" "F.Paste")
			(net "BMC_DEBUG_RXD")
		)
		(pad "G2" smd circle
			(at -7.599934 -3.599942 270)
			(size 0.3683 0.3683)
			(layers "F.Cu" "F.Mask" "F.Paste")
			(net "BMC_NODE1_JTAG_TMS")
		)
		(pad "G3" smd circle
			(at -6.800088 -3.599942 270)
			(size 0.3683 0.3683)
			(layers "F.Cu" "F.Mask" "F.Paste")
			(net "N3975090755")
		)
		(pad "G4" smd circle
			(at -5.999988 -3.599942 270)
			(size 0.3683 0.3683)
			(layers "F.Cu" "F.Mask" "F.Paste")
			(net "Net_532")
		)
		(pad "G5" smd circle
			(at -5.199888 -3.599942 270)
			(size 0.3683 0.3683)
			(layers "F.Cu" "F.Mask" "F.Paste")
			(net "GND")
		)
		(pad "G18" smd circle
			(at 5.199888 -3.599942 270)
			(size 0.3683 0.3683)
			(layers "F.Cu" "F.Mask" "F.Paste")
			(net "Net_1742")
		)
		(pad "G19" smd circle
			(at 5.999988 -3.599942 270)
			(size 0.3683 0.3683)
			(layers "F.Cu" "F.Mask" "F.Paste")
			(net "Net_1745")
		)
		(pad "G20" smd circle
			(at 6.800088 -3.599942 270)
			(size 0.3683 0.3683)
			(layers "F.Cu" "F.Mask" "F.Paste")
			(net "BMC_NODE1_VCC_1V8_PCIE")
		)
		(pad "G21" smd circle
			(at 7.599934 -3.599942 270)
			(size 0.3683 0.3683)
			(layers "F.Cu" "F.Mask" "F.Paste")
			(net "CLK_100M_BMC_NODE1_DN")
		)
		(pad "G22" smd circle
			(at 8.400034 -3.599942 270)
			(size 0.3683 0.3683)
			(layers "F.Cu" "F.Mask" "F.Paste")
			(net "CLK_100M_BMC_NODE1_DP")
		)
		(pad "H1" smd circle
			(at -8.400034 -2.800096 270)
			(size 0.3683 0.3683)
			(layers "F.Cu" "F.Mask" "F.Paste")
			(net "GND")
		)
		(pad "H2" smd circle
			(at -7.599934 -2.800096 270)
			(size 0.3683 0.3683)
			(layers "F.Cu" "F.Mask" "F.Paste")
			(net "GND")
		)
		(pad "H3" smd circle
			(at -6.800088 -2.800096 270)
			(size 0.3683 0.3683)
			(layers "F.Cu" "F.Mask" "F.Paste")
			(net "GND")
		)
		(pad "H4" smd circle
			(at -5.999988 -2.800096 270)
			(size 0.3683 0.3683)
			(layers "F.Cu" "F.Mask" "F.Paste")
			(net "GND")
		)
		(pad "H5" smd circle
			(at -5.199888 -2.800096 270)
			(size 0.3683 0.3683)
			(layers "F.Cu" "F.Mask" "F.Paste")
			(net "BMC_DEBUG_TXD")
		)
		(pad "H6" smd circle
			(at -4.400042 -2.800096 270)
			(size 0.3683 0.3683)
			(layers "F.Cu" "F.Mask" "F.Paste")
			(net "P3V3_NODE1")
		)
		(pad "H17" smd circle
			(at 4.400042 -2.800096 270)
			(size 0.3683 0.3683)
			(layers "F.Cu" "F.Mask" "F.Paste")
			(net "P3V3_NODE1")
		)
		(pad "H18" smd circle
			(at 5.199888 -2.800096 270)
			(size 0.3683 0.3683)
			(layers "F.Cu" "F.Mask" "F.Paste")
			(net "Net_1712")
		)
		(pad "H19" smd circle
			(at 5.999988 -2.800096 270)
			(size 0.3683 0.3683)
			(layers "F.Cu" "F.Mask" "F.Paste")
			(net "Net_548")
		)
		(pad "H20" smd circle
			(at 6.800088 -2.800096 270)
			(size 0.3683 0.3683)
			(layers "F.Cu" "F.Mask" "F.Paste")
			(net "Net_547")
		)
		(pad "H21" smd circle
			(at 7.599934 -2.800096 270)
			(size 0.3683 0.3683)
			(layers "F.Cu" "F.Mask" "F.Paste")
			(net "BMC_NODE1_VCC_1V8_PCIE")
		)
		(pad "H22" smd circle
			(at 8.400034 -2.800096 270)
			(size 0.3683 0.3683)
			(layers "F.Cu" "F.Mask" "F.Paste")
			(net "BMC_NODE1_VCC_1V8_PCIE")
		)
		(pad "J1" smd circle
			(at -8.400034 -1.999996 270)
			(size 0.3683 0.3683)
			(layers "F.Cu" "F.Mask" "F.Paste")
			(net "Net_533")
		)
		(pad "J2" smd circle
			(at -7.599934 -1.999996 270)
			(size 0.3683 0.3683)
			(layers "F.Cu" "F.Mask" "F.Paste")
			(net "Net_528")
		)
		(pad "J3" smd circle
			(at -6.800088 -1.999996 270)
			(size 0.3683 0.3683)
			(layers "F.Cu" "F.Mask" "F.Paste")
			(net "GND")
		)
		(pad "J4" smd circle
			(at -5.999988 -1.999996 270)
			(size 0.3683 0.3683)
			(layers "F.Cu" "F.Mask" "F.Paste")
			(net "Net_1749")
		)
		(pad "J5" smd circle
			(at -5.199888 -1.999996 270)
			(size 0.3683 0.3683)
			(layers "F.Cu" "F.Mask" "F.Paste")
			(net "Net_1748")
		)
		(pad "J6" smd circle
			(at -4.400042 -1.999996 270)
			(size 0.3683 0.3683)
			(layers "F.Cu" "F.Mask" "F.Paste")
			(net "P3V3_NODE1")
		)
		(pad "J9" smd circle
			(at -1.999996 -1.999996 270)
			(size 0.3683 0.3683)
			(layers "F.Cu" "F.Mask" "F.Paste")
			(net "GND")
		)
		(pad "J10" smd circle
			(at -1.199896 -1.999996 270)
			(size 0.3683 0.3683)
			(layers "F.Cu" "F.Mask" "F.Paste")
			(net "GND")
		)
		(pad "J11" smd circle
			(at -0.40005 -1.999996 270)
			(size 0.3683 0.3683)
			(layers "F.Cu" "F.Mask" "F.Paste")
			(net "GND")
		)
		(pad "J12" smd circle
			(at 0.40005 -1.999996 270)
			(size 0.3683 0.3683)
			(layers "F.Cu" "F.Mask" "F.Paste")
			(net "GND")
		)
		(pad "J13" smd circle
			(at 1.199896 -1.999996 270)
			(size 0.3683 0.3683)
			(layers "F.Cu" "F.Mask" "F.Paste")
			(net "GND")
		)
		(pad "J14" smd circle
			(at 1.999996 -1.999996 270)
			(size 0.3683 0.3683)
			(layers "F.Cu" "F.Mask" "F.Paste")
			(net "GND")
		)
		(pad "J17" smd circle
			(at 4.400042 -1.999996 270)
			(size 0.3683 0.3683)
			(layers "F.Cu" "F.Mask" "F.Paste")
			(net "P3V3_NODE1")
		)
		(pad "J18" smd circle
			(at 5.199888 -1.999996 270)
			(size 0.3683 0.3683)
			(layers "F.Cu" "F.Mask" "F.Paste")
			(net "GND")
		)
		(pad "J19" smd circle
			(at 5.999988 -1.999996 270)
			(size 0.3683 0.3683)
			(layers "F.Cu" "F.Mask" "F.Paste")
			(net "GND")
		)
		(pad "J20" smd circle
			(at 6.800088 -1.999996 270)
			(size 0.3683 0.3683)
			(layers "F.Cu" "F.Mask" "F.Paste")
			(net "Net_1711")
		)
		(pad "J21" smd circle
			(at 7.599934 -1.999996 270)
			(size 0.3683 0.3683)
			(layers "F.Cu" "F.Mask" "F.Paste")
			(net "Net_546")
		)
		(pad "J22" smd circle
			(at 8.400034 -1.999996 270)
			(size 0.3683 0.3683)
			(layers "F.Cu" "F.Mask" "F.Paste")
			(net "IRQ_LVC3_CPU_NODE1_WAKE_R_L")
		)
		(pad "K1" smd circle
			(at -8.400034 -1.199896 270)
			(size 0.3683 0.3683)
			(layers "F.Cu" "F.Mask" "F.Paste")
			(net "TP_BMC_NODE1_ADCVREFP")
		)
		(pad "K2" smd circle
			(at -7.599934 -1.199896 270)
			(size 0.3683 0.3683)
			(layers "F.Cu" "F.Mask" "F.Paste")
			(net "TP_BMC_NODE1_ADCVREFN")
		)
		(pad "K3" smd circle
			(at -6.800088 -1.199896 270)
			(size 0.3683 0.3683)
			(layers "F.Cu" "F.Mask" "F.Paste")
			(net "Net_534")
		)
		(pad "K4" smd circle
			(at -5.999988 -1.199896 270)
			(size 0.3683 0.3683)
			(layers "F.Cu" "F.Mask" "F.Paste")
			(net "Net_530")
		)
		(pad "K5" smd circle
			(at -5.199888 -1.199896 270)
			(size 0.3683 0.3683)
			(layers "F.Cu" "F.Mask" "F.Paste")
			(net "GND")
		)
		(pad "K6" smd circle
			(at -4.400042 -1.199896 270)
			(size 0.3683 0.3683)
			(layers "F.Cu" "F.Mask" "F.Paste")
			(net "P1V26_BMC_NODE1")
		)
		(pad "K9" smd circle
			(at -1.999996 -1.199896 270)
			(size 0.3683 0.3683)
			(layers "F.Cu" "F.Mask" "F.Paste")
			(net "GND")
		)
		(pad "K10" smd circle
			(at -1.199896 -1.199896 270)
			(size 0.3683 0.3683)
			(layers "F.Cu" "F.Mask" "F.Paste")
			(net "GND")
		)
		(pad "K11" smd circle
			(at -0.40005 -1.199896 270)
			(size 0.3683 0.3683)
			(layers "F.Cu" "F.Mask" "F.Paste")
			(net "GND")
		)
		(pad "K12" smd circle
			(at 0.40005 -1.199896 270)
			(size 0.3683 0.3683)
			(layers "F.Cu" "F.Mask" "F.Paste")
			(net "GND")
		)
		(pad "K13" smd circle
			(at 1.199896 -1.199896 270)
			(size 0.3683 0.3683)
			(layers "F.Cu" "F.Mask" "F.Paste")
			(net "GND")
		)
		(pad "K14" smd circle
			(at 1.999996 -1.199896 270)
			(size 0.3683 0.3683)
			(layers "F.Cu" "F.Mask" "F.Paste")
			(net "GND")
		)
		(pad "K17" smd circle
			(at 4.400042 -1.199896 270)
			(size 0.3683 0.3683)
			(layers "F.Cu" "F.Mask" "F.Paste")
			(net "P1V26_BMC_NODE1")
		)
		(pad "K18" smd circle
			(at 5.199888 -1.199896 270)
			(size 0.3683 0.3683)
			(layers "F.Cu" "F.Mask" "F.Paste")
			(net "BMC_ROMA23")
		)
		(pad "K19" smd circle
			(at 5.999988 -1.199896 270)
			(size 0.3683 0.3683)
			(layers "F.Cu" "F.Mask" "F.Paste")
			(net "RST_BMC_NODE1_PERST_L")
		)
		(pad "K20" smd circle
			(at 6.800088 -1.199896 270)
			(size 0.3683 0.3683)
			(layers "F.Cu" "F.Mask" "F.Paste")
			(net "GND")
		)
		(pad "K21" smd circle
			(at 7.599934 -1.199896 270)
			(size 0.3683 0.3683)
			(layers "F.Cu" "F.Mask" "F.Paste")
			(net "PU_I2C_BMC_SCL")
		)
		(pad "K22" smd circle
			(at 8.400034 -1.199896 270)
			(size 0.3683 0.3683)
			(layers "F.Cu" "F.Mask" "F.Paste")
			(net "PU_I2C_BMC_SDA")
		)
		(pad "L1" smd circle
			(at -8.400034 -0.40005 270)
			(size 0.3683 0.3683)
			(layers "F.Cu" "F.Mask" "F.Paste")
			(net "GND")
		)
		(pad "L2" smd circle
			(at -7.599934 -0.40005 270)
			(size 0.3683 0.3683)
			(layers "F.Cu" "F.Mask" "F.Paste")
			(net "GND")
		)
		(pad "L3" smd circle
			(at -6.800088 -0.40005 270)
			(size 0.3683 0.3683)
			(layers "F.Cu" "F.Mask" "F.Paste")
			(net "GND")
		)
		(pad "L4" smd circle
			(at -5.999988 -0.40005 270)
			(size 0.3683 0.3683)
			(layers "F.Cu" "F.Mask" "F.Paste")
			(net "GND")
		)
		(pad "L5" smd circle
			(at -5.199888 -0.40005 270)
			(size 0.3683 0.3683)
			(layers "F.Cu" "F.Mask" "F.Paste")
			(net "GND")
		)
	)
)
